(kicad_pcb
	(version 20260206)
	(generator "pcbnew")
	(generator_version "10.0")
	(general
		(thickness 1.6)
		(legacy_teardrops no)
	)
	(paper "A4")
	(title_block
		(title "03242023_DA0F0TMBIJ0_F0T_Motherboard_J_brd_V01_OCP.brd")
		(comment 1 "Grand Teton / footprints 2268-2274 of 6105")
	)
	(layers
		(0 "F.Cu" signal "TOP")
		(4 "In1.Cu" signal "GND")
		(6 "In2.Cu" signal "IN1")
		(8 "In3.Cu" signal "GND1")
		(10 "In4.Cu" signal "IN2")
		(12 "In5.Cu" signal "GND2")
		(14 "In6.Cu" signal "IN3")
		(16 "In7.Cu" signal "GND3")
		(18 "In8.Cu" signal "VCC")
		(20 "In9.Cu" signal "VCC1")
		(22 "In10.Cu" signal "GND4")
		(24 "In11.Cu" signal "IN4")
		(26 "In12.Cu" signal "GND5")
		(28 "In13.Cu" signal "IN5")
		(30 "In14.Cu" signal "GND6")
		(32 "In15.Cu" signal "IN6")
		(34 "In16.Cu" signal "GND7")
		(2 "B.Cu" signal "BOTTOM")
		(9 "F.Adhes" user "F.Adhesive")
		(11 "B.Adhes" user "B.Adhesive")
		(13 "F.Paste" user "Package Geometry/Pastemask Top")
		(15 "B.Paste" user "Package Geometry/Pastemask Bottom")
		(5 "F.SilkS" user "Ref Des/Silkscreen Top")
		(7 "B.SilkS" user "Ref Des/Silkscreen Bottom")
		(1 "F.Mask" user "Board Geometry/Soldermask Top")
		(3 "B.Mask" user "Board Geometry/Soldermask Bottom")
		(17 "Dwgs.User" user "User.Drawings")
		(19 "Cmts.User" user "User.Comments")
		(21 "Eco1.User" user "User.Eco1")
		(23 "Eco2.User" user "User.Eco2")
		(25 "Edge.Cuts" user "Board Geometry/Outline")
		(27 "Margin" user)
		(31 "F.CrtYd" user "Package Geometry/Place Bound Top")
		(29 "B.CrtYd" user "Package Geometry/Place Bound Bottom")
		(35 "F.Fab" user "Ref Des/Assembly Top")
		(33 "B.Fab" user "Ref Des/Assembly Bottom")
	)
	(footprint ""
		(layer "F.Cu")
		(at 100.566982 -333.804514 -90)
		(property "Reference" "PC563_P1_1"
			(at 0 0 270)
			(layer "F.SilkS")
			(hide yes)
			(effects
				(font
					(size 1.27 1.27)
				)
			)
		)
		(property "Value" ""
			(at 0 0 270)
			(layer "F.Fab")
			(effects
				(font
					(size 1.27 1.27)
				)
			)
		)
		(duplicate_pad_numbers_are_jumpers no)
		(fp_line
			(start -0.7874 0.4064)
			(end -0.7874 -0.4064)
			(stroke
				(width 0.1524)
				(type default)
			)
			(layer "F.SilkS")
		)
		(fp_line
			(start 0.7874 0.4064)
			(end -0.7874 0.4064)
			(stroke
				(width 0.1524)
				(type default)
			)
			(layer "F.SilkS")
		)
		(fp_line
			(start -0.7874 -0.4064)
			(end 0.7874 -0.4064)
			(stroke
				(width 0.1524)
				(type default)
			)
			(layer "F.SilkS")
		)
		(fp_line
			(start 0.7874 -0.4064)
			(end 0.7874 0.4064)
			(stroke
				(width 0.1524)
				(type default)
			)
			(layer "F.SilkS")
		)
		(fp_line
			(start -0.67945 0.3048)
			(end -0.67945 -0.305054)
			(stroke
				(width 0.1)
				(type default)
			)
			(layer "F.Fab")
		)
		(fp_line
			(start -0.12065 0.3048)
			(end -0.67945 0.3048)
			(stroke
				(width 0.1)
				(type default)
			)
			(layer "F.Fab")
		)
		(fp_line
			(start 0.120396 0.3048)
			(end 0.120396 0.2794)
			(stroke
				(width 0.1)
				(type default)
			)
			(layer "F.Fab")
		)
		(fp_line
			(start 0.67945 0.3048)
			(end 0.120396 0.3048)
			(stroke
				(width 0.1)
				(type default)
			)
			(layer "F.Fab")
		)
		(fp_line
			(start -0.12065 0.2794)
			(end -0.12065 0.3048)
			(stroke
				(width 0.1)
				(type default)
			)
			(layer "F.Fab")
		)
		(fp_line
			(start 0.120396 0.2794)
			(end -0.12065 0.2794)
			(stroke
				(width 0.1)
				(type default)
			)
			(layer "F.Fab")
		)
		(fp_line
			(start -0.12065 -0.2794)
			(end 0.12065 -0.2794)
			(stroke
				(width 0.1)
				(type default)
			)
			(layer "F.Fab")
		)
		(fp_line
			(start 0.12065 -0.2794)
			(end 0.12065 -0.3048)
			(stroke
				(width 0.1)
				(type default)
			)
			(layer "F.Fab")
		)
		(fp_line
			(start 0.12065 -0.3048)
			(end 0.67945 -0.3048)
			(stroke
				(width 0.1)
				(type default)
			)
			(layer "F.Fab")
		)
		(fp_line
			(start 0.67945 -0.3048)
			(end 0.67945 0.3048)
			(stroke
				(width 0.1)
				(type default)
			)
			(layer "F.Fab")
		)
		(fp_line
			(start -0.67945 -0.305054)
			(end -0.12065 -0.305054)
			(stroke
				(width 0.1)
				(type default)
			)
			(layer "F.Fab")
		)
		(fp_line
			(start -0.12065 -0.305054)
			(end -0.12065 -0.2794)
			(stroke
				(width 0.1)
				(type default)
			)
			(layer "F.Fab")
		)
		(pad "1" smd circle
			(at -0.40005 0 270)
			(size 0 0)
			(layers "F.Cu" "F.Mask" "F.Paste")
			(net "SW_P12V_PVCCIN_CPU1_FLT")
		)
		(pad "2" smd circle
			(at 0.40005 0 270)
			(size 0 0)
			(layers "F.Cu" "F.Mask" "F.Paste")
			(net "GND")
		)
	)
	(footprint ""
		(layer "F.Cu")
		(at 421.15359 -180.749194 -90)
		(property "Reference" "PR1707"
			(at 0 0 270)
			(layer "F.SilkS")
			(hide yes)
			(effects
				(font
					(size 1.27 1.27)
				)
			)
		)
		(property "Value" ""
			(at 0 0 270)
			(layer "F.Fab")
			(effects
				(font
					(size 1.27 1.27)
				)
			)
		)
		(duplicate_pad_numbers_are_jumpers no)
		(fp_line
			(start -0.7874 0.4064)
			(end -0.7874 -0.4064)
			(stroke
				(width 0.1524)
				(type default)
			)
			(layer "F.SilkS")
		)
		(fp_line
			(start 0.7874 0.4064)
			(end -0.7874 0.4064)
			(stroke
				(width 0.1524)
				(type default)
			)
			(layer "F.SilkS")
		)
		(fp_line
			(start -0.7874 -0.4064)
			(end 0.7874 -0.4064)
			(stroke
				(width 0.1524)
				(type default)
			)
			(layer "F.SilkS")
		)
		(fp_line
			(start 0.7874 -0.4064)
			(end 0.7874 0.4064)
			(stroke
				(width 0.1524)
				(type default)
			)
			(layer "F.SilkS")
		)
		(fp_line
			(start -0.67945 0.3048)
			(end -0.67945 -0.305054)
			(stroke
				(width 0.1)
				(type default)
			)
			(layer "F.Fab")
		)
		(fp_line
			(start -0.12065 0.3048)
			(end -0.67945 0.3048)
			(stroke
				(width 0.1)
				(type default)
			)
			(layer "F.Fab")
		)
		(fp_line
			(start 0.120396 0.3048)
			(end 0.120396 0.2794)
			(stroke
				(width 0.1)
				(type default)
			)
			(layer "F.Fab")
		)
		(fp_line
			(start 0.67945 0.3048)
			(end 0.120396 0.3048)
			(stroke
				(width 0.1)
				(type default)
			)
			(layer "F.Fab")
		)
		(fp_line
			(start -0.12065 0.2794)
			(end -0.12065 0.3048)
			(stroke
				(width 0.1)
				(type default)
			)
			(layer "F.Fab")
		)
		(fp_line
			(start 0.120396 0.2794)
			(end -0.12065 0.2794)
			(stroke
				(width 0.1)
				(type default)
			)
			(layer "F.Fab")
		)
		(fp_line
			(start -0.12065 -0.2794)
			(end 0.12065 -0.2794)
			(stroke
				(width 0.1)
				(type default)
			)
			(layer "F.Fab")
		)
		(fp_line
			(start 0.12065 -0.2794)
			(end 0.12065 -0.3048)
			(stroke
				(width 0.1)
				(type default)
			)
			(layer "F.Fab")
		)
		(fp_line
			(start 0.12065 -0.3048)
			(end 0.67945 -0.3048)
			(stroke
				(width 0.1)
				(type default)
			)
			(layer "F.Fab")
		)
		(fp_line
			(start 0.67945 -0.3048)
			(end 0.67945 0.3048)
			(stroke
				(width 0.1)
				(type default)
			)
			(layer "F.Fab")
		)
		(fp_line
			(start -0.67945 -0.305054)
			(end -0.12065 -0.305054)
			(stroke
				(width 0.1)
				(type default)
			)
			(layer "F.Fab")
		)
		(fp_line
			(start -0.12065 -0.305054)
			(end -0.12065 -0.2794)
			(stroke
				(width 0.1)
				(type default)
			)
			(layer "F.Fab")
		)
		(pad "1" smd circle
			(at -0.40005 0 270)
			(size 0 0)
			(layers "F.Cu" "F.Mask" "F.Paste")
			(net "PVCCINFAON_CPU0_LSET2")
		)
		(pad "2" smd circle
			(at 0.40005 0 270)
			(size 0 0)
			(layers "F.Cu" "F.Mask" "F.Paste")
			(net "GND")
		)
	)
	(footprint ""
		(layer "F.Cu")
		(at 259.89788 -46.634146 90)
		(property "Reference" "PC2198"
			(at 0 0 90)
			(layer "F.SilkS")
			(hide yes)
			(effects
				(font
					(size 1.27 1.27)
				)
			)
		)
		(property "Value" ""
			(at 0 0 90)
			(layer "F.Fab")
			(effects
				(font
					(size 1.27 1.27)
				)
			)
		)
		(duplicate_pad_numbers_are_jumpers no)
		(fp_line
			(start 0.7874 -0.4064)
			(end 0.7874 0.4064)
			(stroke
				(width 0.1524)
				(type default)
			)
			(layer "F.SilkS")
		)
		(fp_line
			(start -0.7874 -0.4064)
			(end 0.7874 -0.4064)
			(stroke
				(width 0.1524)
				(type default)
			)
			(layer "F.SilkS")
		)
		(fp_line
			(start 0.7874 0.4064)
			(end -0.7874 0.4064)
			(stroke
				(width 0.1524)
				(type default)
			)
			(layer "F.SilkS")
		)
		(fp_line
			(start -0.7874 0.4064)
			(end -0.7874 -0.4064)
			(stroke
				(width 0.1524)
				(type default)
			)
			(layer "F.SilkS")
		)
		(fp_line
			(start -0.12065 -0.305054)
			(end -0.12065 -0.2794)
			(stroke
				(width 0.1)
				(type default)
			)
			(layer "F.Fab")
		)
		(fp_line
			(start -0.67945 -0.305054)
			(end -0.12065 -0.305054)
			(stroke
				(width 0.1)
				(type default)
			)
			(layer "F.Fab")
		)
		(fp_line
			(start 0.67945 -0.3048)
			(end 0.67945 0.3048)
			(stroke
				(width 0.1)
				(type default)
			)
			(layer "F.Fab")
		)
		(fp_line
			(start 0.12065 -0.3048)
			(end 0.67945 -0.3048)
			(stroke
				(width 0.1)
				(type default)
			)
			(layer "F.Fab")
		)
		(fp_line
			(start 0.12065 -0.2794)
			(end 0.12065 -0.3048)
			(stroke
				(width 0.1)
				(type default)
			)
			(layer "F.Fab")
		)
		(fp_line
			(start -0.12065 -0.2794)
			(end 0.12065 -0.2794)
			(stroke
				(width 0.1)
				(type default)
			)
			(layer "F.Fab")
		)
		(fp_line
			(start 0.120396 0.2794)
			(end -0.12065 0.2794)
			(stroke
				(width 0.1)
				(type default)
			)
			(layer "F.Fab")
		)
		(fp_line
			(start -0.12065 0.2794)
			(end -0.12065 0.3048)
			(stroke
				(width 0.1)
				(type default)
			)
			(layer "F.Fab")
		)
		(fp_line
			(start 0.67945 0.3048)
			(end 0.120396 0.3048)
			(stroke
				(width 0.1)
				(type default)
			)
			(layer "F.Fab")
		)
		(fp_line
			(start 0.120396 0.3048)
			(end 0.120396 0.2794)
			(stroke
				(width 0.1)
				(type default)
			)
			(layer "F.Fab")
		)
		(fp_line
			(start -0.12065 0.3048)
			(end -0.67945 0.3048)
			(stroke
				(width 0.1)
				(type default)
			)
			(layer "F.Fab")
		)
		(fp_line
			(start -0.67945 0.3048)
			(end -0.67945 -0.305054)
			(stroke
				(width 0.1)
				(type default)
			)
			(layer "F.Fab")
		)
		(pad "1" smd circle
			(at -0.40005 0 90)
			(size 0 0)
			(layers "F.Cu" "F.Mask" "F.Paste")
			(net "P12V_AUX")
		)
		(pad "2" smd circle
			(at 0.40005 0 90)
			(size 0 0)
			(layers "F.Cu" "F.Mask" "F.Paste")
			(net "GND")
		)
	)
	(footprint ""
		(layer "F.Cu")
		(at 104.723438 -315.66739 90)
		(property "Reference" "PC589"
			(at 0 0 90)
			(layer "F.SilkS")
			(hide yes)
			(effects
				(font
					(size 1.27 1.27)
				)
			)
		)
		(property "Value" ""
			(at 0 0 90)
			(layer "F.Fab")
			(effects
				(font
					(size 1.27 1.27)
				)
			)
		)
		(duplicate_pad_numbers_are_jumpers no)
		(fp_line
			(start 2.750058 0.999998)
			(end -2.750058 0.999998)
			(stroke
				(width 0.1524)
				(type default)
			)
			(layer "F.SilkS")
		)
		(fp_circle
			(center 0 0.999998)
			(end 0 3.750056)
			(stroke
				(width 0.1524)
				(type default)
			)
			(fill no)
			(layer "F.SilkS")
		)
		(fp_poly
			(pts
				(arc
					(start 2.750058 0.999998)
					(mid 0 3.750056)
					(end -2.750058 0.999998)
				)
			)
			(stroke
				(width 0)
				(type default)
			)
			(fill yes)
			(layer "F.SilkS")
		)
		(fp_circle
			(center 0 0.999998)
			(end 0 3.750056)
			(stroke
				(width 0.1)
				(type default)
			)
			(fill no)
			(layer "F.Fab")
		)
		(pad "1" thru_hole rect
			(at 0 0 90)
			(size 1.5748 1.5748)
			(drill 1.0668)
			(layers "*.Cu" "*.Mask")
			(remove_unused_layers no)
			(net "PVCCIN_CPU1")
			(clearance 0)
			(padstack
				(mode front_inner_back)
				(layer "Inner"
					(shape circle)
					(size 1.5748 1.5748)
					(clearance 0)
				)
				(layer "B.Cu"
					(shape rect)
					(size 1.5748 1.5748)
					(clearance 0)
				)
			)
		)
		(pad "2" thru_hole circle
			(at 0 1.999996 90)
			(size 1.5748 1.5748)
			(drill 1.0668)
			(layers "*.Cu" "*.Mask")
			(remove_unused_layers no)
			(net "GND")
			(clearance 0)
		)
	)
	(footprint ""
		(layer "F.Cu")
		(at 386.544312 -76.39685 90)
		(property "Reference" "PC1234"
			(at 0 0 90)
			(layer "F.SilkS")
			(hide yes)
			(effects
				(font
					(size 1.27 1.27)
				)
			)
		)
		(property "Value" ""
			(at 0 0 90)
			(layer "F.Fab")
			(effects
				(font
					(size 1.27 1.27)
				)
			)
		)
		(duplicate_pad_numbers_are_jumpers no)
		(fp_line
			(start 0.7874 -0.4064)
			(end 0.7874 0.4064)
			(stroke
				(width 0.1524)
				(type default)
			)
			(layer "F.SilkS")
		)
		(fp_line
			(start -0.7874 -0.4064)
			(end 0.7874 -0.4064)
			(stroke
				(width 0.1524)
				(type default)
			)
			(layer "F.SilkS")
		)
		(fp_line
			(start 0.7874 0.4064)
			(end -0.7874 0.4064)
			(stroke
				(width 0.1524)
				(type default)
			)
			(layer "F.SilkS")
		)
		(fp_line
			(start -0.7874 0.4064)
			(end -0.7874 -0.4064)
			(stroke
				(width 0.1524)
				(type default)
			)
			(layer "F.SilkS")
		)
		(fp_line
			(start -0.12065 -0.305054)
			(end -0.12065 -0.2794)
			(stroke
				(width 0.1)
				(type default)
			)
			(layer "F.Fab")
		)
		(fp_line
			(start -0.67945 -0.305054)
			(end -0.12065 -0.305054)
			(stroke
				(width 0.1)
				(type default)
			)
			(layer "F.Fab")
		)
		(fp_line
			(start 0.67945 -0.3048)
			(end 0.67945 0.3048)
			(stroke
				(width 0.1)
				(type default)
			)
			(layer "F.Fab")
		)
		(fp_line
			(start 0.12065 -0.3048)
			(end 0.67945 -0.3048)
			(stroke
				(width 0.1)
				(type default)
			)
			(layer "F.Fab")
		)
		(fp_line
			(start 0.12065 -0.2794)
			(end 0.12065 -0.3048)
			(stroke
				(width 0.1)
				(type default)
			)
			(layer "F.Fab")
		)
		(fp_line
			(start -0.12065 -0.2794)
			(end 0.12065 -0.2794)
			(stroke
				(width 0.1)
				(type default)
			)
			(layer "F.Fab")
		)
		(fp_line
			(start 0.120396 0.2794)
			(end -0.12065 0.2794)
			(stroke
				(width 0.1)
				(type default)
			)
			(layer "F.Fab")
		)
		(fp_line
			(start -0.12065 0.2794)
			(end -0.12065 0.3048)
			(stroke
				(width 0.1)
				(type default)
			)
			(layer "F.Fab")
		)
		(fp_line
			(start 0.67945 0.3048)
			(end 0.120396 0.3048)
			(stroke
				(width 0.1)
				(type default)
			)
			(layer "F.Fab")
		)
		(fp_line
			(start 0.120396 0.3048)
			(end 0.120396 0.2794)
			(stroke
				(width 0.1)
				(type default)
			)
			(layer "F.Fab")
		)
		(fp_line
			(start -0.12065 0.3048)
			(end -0.67945 0.3048)
			(stroke
				(width 0.1)
				(type default)
			)
			(layer "F.Fab")
		)
		(fp_line
			(start -0.67945 0.3048)
			(end -0.67945 -0.305054)
			(stroke
				(width 0.1)
				(type default)
			)
			(layer "F.Fab")
		)
		(pad "1" smd circle
			(at -0.40005 0 90)
			(size 0 0)
			(layers "F.Cu" "F.Mask" "F.Paste")
			(net "SW_P1V8_PCH_AUX_FLT")
		)
		(pad "2" smd circle
			(at 0.40005 0 90)
			(size 0 0)
			(layers "F.Cu" "F.Mask" "F.Paste")
			(net "GND")
		)
	)
	(footprint ""
		(layer "F.Cu")
		(at 99.589082 -74.911966 -90)
		(property "Reference" "R3073"
			(at 0 0 270)
			(layer "F.SilkS")
			(hide yes)
			(effects
				(font
					(size 1.27 1.27)
				)
			)
		)
		(property "Value" ""
			(at 0 0 270)
			(layer "F.Fab")
			(effects
				(font
					(size 1.27 1.27)
				)
			)
		)
		(duplicate_pad_numbers_are_jumpers no)
		(fp_line
			(start -0.7874 0.4064)
			(end -0.7874 -0.4064)
			(stroke
				(width 0.1524)
				(type default)
			)
			(layer "F.SilkS")
		)
		(fp_line
			(start 0.7874 0.4064)
			(end -0.7874 0.4064)
			(stroke
				(width 0.1524)
				(type default)
			)
			(layer "F.SilkS")
		)
		(fp_line
			(start -0.7874 -0.4064)
			(end 0.7874 -0.4064)
			(stroke
				(width 0.1524)
				(type default)
			)
			(layer "F.SilkS")
		)
		(fp_line
			(start 0.7874 -0.4064)
			(end 0.7874 0.4064)
			(stroke
				(width 0.1524)
				(type default)
			)
			(layer "F.SilkS")
		)
		(fp_line
			(start -0.67945 0.3048)
			(end -0.67945 -0.305054)
			(stroke
				(width 0.1)
				(type default)
			)
			(layer "F.Fab")
		)
		(fp_line
			(start -0.12065 0.3048)
			(end -0.67945 0.3048)
			(stroke
				(width 0.1)
				(type default)
			)
			(layer "F.Fab")
		)
		(fp_line
			(start 0.120396 0.3048)
			(end 0.120396 0.2794)
			(stroke
				(width 0.1)
				(type default)
			)
			(layer "F.Fab")
		)
		(fp_line
			(start 0.67945 0.3048)
			(end 0.120396 0.3048)
			(stroke
				(width 0.1)
				(type default)
			)
			(layer "F.Fab")
		)
		(fp_line
			(start -0.12065 0.2794)
			(end -0.12065 0.3048)
			(stroke
				(width 0.1)
				(type default)
			)
			(layer "F.Fab")
		)
		(fp_line
			(start 0.120396 0.2794)
			(end -0.12065 0.2794)
			(stroke
				(width 0.1)
				(type default)
			)
			(layer "F.Fab")
		)
		(fp_line
			(start -0.12065 -0.2794)
			(end 0.12065 -0.2794)
			(stroke
				(width 0.1)
				(type default)
			)
			(layer "F.Fab")
		)
		(fp_line
			(start 0.12065 -0.2794)
			(end 0.12065 -0.3048)
			(stroke
				(width 0.1)
				(type default)
			)
			(layer "F.Fab")
		)
		(fp_line
			(start 0.12065 -0.3048)
			(end 0.67945 -0.3048)
			(stroke
				(width 0.1)
				(type default)
			)
			(layer "F.Fab")
		)
		(fp_line
			(start 0.67945 -0.3048)
			(end 0.67945 0.3048)
			(stroke
				(width 0.1)
				(type default)
			)
			(layer "F.Fab")
		)
		(fp_line
			(start -0.67945 -0.305054)
			(end -0.12065 -0.305054)
			(stroke
				(width 0.1)
				(type default)
			)
			(layer "F.Fab")
		)
		(fp_line
			(start -0.12065 -0.305054)
			(end -0.12065 -0.2794)
			(stroke
				(width 0.1)
				(type default)
			)
			(layer "F.Fab")
		)
		(pad "1" smd circle
			(at -0.40005 0 270)
			(size 0 0)
			(layers "F.Cu" "F.Mask" "F.Paste")
			(net "LED_FM_PCH_SLP_S4_N")
		)
		(pad "2" smd circle
			(at 0.40005 0 270)
			(size 0 0)
			(layers "F.Cu" "F.Mask" "F.Paste")
			(net "P3V3_AUX")
		)
	)
	(footprint ""
		(layer "F.Cu")
		(at 122.390154 -408.517344 -90)
		(property "Reference" "C1517"
			(at 0 0 270)
			(layer "F.SilkS")
			(hide yes)
			(effects
				(font
					(size 1.27 1.27)
				)
			)
		)
		(property "Value" ""
			(at 0 0 270)
			(layer "F.Fab")
			(effects
				(font
					(size 1.27 1.27)
				)
			)
		)
		(duplicate_pad_numbers_are_jumpers no)
		(fp_line
			(start -0.299974 0.150114)
			(end -0.299974 -0.150114)
			(stroke
				(width 0.1)
				(type default)
			)
			(layer "F.Fab")
		)
		(fp_line
			(start 0.299974 0.150114)
			(end -0.299974 0.150114)
			(stroke
				(width 0.1)
				(type default)
			)
			(layer "F.Fab")
		)
		(fp_line
			(start -0.299974 -0.150114)
			(end 0.299974 -0.150114)
			(stroke
				(width 0.1)
				(type default)
			)
			(layer "F.Fab")
		)
		(fp_line
			(start 0.299974 -0.150114)
			(end 0.299974 0.150114)
			(stroke
				(width 0.1)
				(type default)
			)
			(layer "F.Fab")
		)
		(pad "1" smd rect
			(at -0.2667 0 270)
			(size 0.3048 0.381)
			(layers "F.Cu" "F.Mask" "F.Paste")
			(net "P5E_CPU1_PE3_TX_C_DP<15>")
		)
		(pad "2" smd rect
			(at 0.2667 0 270)
			(size 0.3048 0.381)
			(layers "F.Cu" "F.Mask" "F.Paste")
			(net "P5E_CPU1_PE3_TX_DP<15>")
		)
	)
)
